# S9S_MB_2U (Grand Teton) — schematic netlist excerpt (pin names and nets, part order shuffled) for the footprints in the layout excerpt that follows; sources: Cadence DE-HDL packaged netlist, KiCad conversion of 03242023_DA0F0TMBIJ0_F0T_Motherboard_J_brd_V01_OCP.brd

R714  Q_RES  1K 1% CHIP  pkg 0402LF  page 243 : A = MB_FRU_ADDR2 ; B = GND
R4552  Q_RES  100K 1% CHIP  pkg 0402LF  page 246 : A = HPDB_HSC_PWRGD ; B = GND

(kicad_pcb
	(version 20260206)
	(generator "pcbnew")
	(generator_version "10.0")
	(general
		(thickness 1.6)
		(legacy_teardrops no)
	)
	(paper "A4")
	(title_block
		(title "03242023_DA0F0TMBIJ0_F0T_Motherboard_J_brd_V01_OCP.brd")
		(comment 1 "Grand Teton / footprints 233-234 of 6105")
	)
	(layers
		(0 "F.Cu" signal "TOP")
		(4 "In1.Cu" signal "GND")
		(6 "In2.Cu" signal "IN1")
		(8 "In3.Cu" signal "GND1")
		(10 "In4.Cu" signal "IN2")
		(12 "In5.Cu" signal "GND2")
		(14 "In6.Cu" signal "IN3")
		(16 "In7.Cu" signal "GND3")
		(18 "In8.Cu" signal "VCC")
		(20 "In9.Cu" signal "VCC1")
		(22 "In10.Cu" signal "GND4")
		(24 "In11.Cu" signal "IN4")
		(26 "In12.Cu" signal "GND5")
		(28 "In13.Cu" signal "IN5")
		(30 "In14.Cu" signal "GND6")
		(32 "In15.Cu" signal "IN6")
		(34 "In16.Cu" signal "GND7")
		(2 "B.Cu" signal "BOTTOM")
		(9 "F.Adhes" user "F.Adhesive")
		(11 "B.Adhes" user "B.Adhesive")
		(13 "F.Paste" user "Package Geometry/Pastemask Top")
		(15 "B.Paste" user "Package Geometry/Pastemask Bottom")
		(5 "F.SilkS" user "Ref Des/Silkscreen Top")
		(7 "B.SilkS" user "Ref Des/Silkscreen Bottom")
		(1 "F.Mask" user "Board Geometry/Soldermask Top")
		(3 "B.Mask" user "Board Geometry/Soldermask Bottom")
		(17 "Dwgs.User" user "User.Drawings")
		(19 "Cmts.User" user "User.Comments")
		(21 "Eco1.User" user "User.Eco1")
		(23 "Eco2.User" user "User.Eco2")
		(25 "Edge.Cuts" user "Board Geometry/Outline")
		(27 "Margin" user)
		(31 "F.CrtYd" user "Package Geometry/Place Bound Top")
		(29 "B.CrtYd" user "Package Geometry/Place Bound Bottom")
		(35 "F.Fab" user "Ref Des/Assembly Top")
		(33 "B.Fab" user "Ref Des/Assembly Bottom")
	)
	(footprint ""
		(layer "F.Cu")
		(at 274.69846 -93.741494 180)
		(property "Reference" "R714"
			(at 0 0 180)
			(layer "F.SilkS")
			(hide yes)
			(effects
				(font
					(size 1.27 1.27)
				)
			)
		)
		(property "Value" ""
			(at 0 0 180)
			(layer "F.Fab")
			(effects
				(font
					(size 1.27 1.27)
				)
			)
		)
		(duplicate_pad_numbers_are_jumpers no)
		(fp_line
			(start 0.7874 0.4064)
			(end -0.7874 0.4064)
			(stroke
				(width 0.1524)
				(type default)
			)
			(layer "F.SilkS")
		)
		(fp_line
			(start 0.7874 -0.4064)
			(end 0.7874 0.4064)
			(stroke
				(width 0.1524)
				(type default)
			)
			(layer "F.SilkS")
		)
		(fp_line
			(start -0.7874 0.4064)
			(end -0.7874 -0.4064)
			(stroke
				(width 0.1524)
				(type default)
			)
			(layer "F.SilkS")
		)
		(fp_line
			(start -0.7874 -0.4064)
			(end 0.7874 -0.4064)
			(stroke
				(width 0.1524)
				(type default)
			)
			(layer "F.SilkS")
		)
		(fp_line
			(start 0.67945 0.3048)
			(end 0.120396 0.3048)
			(stroke
				(width 0.1)
				(type default)
			)
			(layer "F.Fab")
		)
		(fp_line
			(start 0.67945 -0.3048)
			(end 0.67945 0.3048)
			(stroke
				(width 0.1)
				(type default)
			)
			(layer "F.Fab")
		)
		(fp_line
			(start 0.12065 -0.2794)
			(end 0.12065 -0.3048)
			(stroke
				(width 0.1)
				(type default)
			)
			(layer "F.Fab")
		)
		(fp_line
			(start 0.12065 -0.3048)
			(end 0.67945 -0.3048)
			(stroke
				(width 0.1)
				(type default)
			)
			(layer "F.Fab")
		)
		(fp_line
			(start 0.120396 0.3048)
			(end 0.120396 0.2794)
			(stroke
				(width 0.1)
				(type default)
			)
			(layer "F.Fab")
		)
		(fp_line
			(start 0.120396 0.2794)
			(end -0.12065 0.2794)
			(stroke
				(width 0.1)
				(type default)
			)
			(layer "F.Fab")
		)
		(fp_line
			(start -0.12065 0.3048)
			(end -0.67945 0.3048)
			(stroke
				(width 0.1)
				(type default)
			)
			(layer "F.Fab")
		)
		(fp_line
			(start -0.12065 0.2794)
			(end -0.12065 0.3048)
			(stroke
				(width 0.1)
				(type default)
			)
			(layer "F.Fab")
		)
		(fp_line
			(start -0.12065 -0.2794)
			(end 0.12065 -0.2794)
			(stroke
				(width 0.1)
				(type default)
			)
			(layer "F.Fab")
		)
		(fp_line
			(start -0.12065 -0.305054)
			(end -0.12065 -0.2794)
			(stroke
				(width 0.1)
				(type default)
			)
			(layer "F.Fab")
		)
		(fp_line
			(start -0.67945 0.3048)
			(end -0.67945 -0.305054)
			(stroke
				(width 0.1)
				(type default)
			)
			(layer "F.Fab")
		)
		(fp_line
			(start -0.67945 -0.305054)
			(end -0.12065 -0.305054)
			(stroke
				(width 0.1)
				(type default)
			)
			(layer "F.Fab")
		)
		(pad "1" smd circle
			(at -0.40005 0 180)
			(size 0 0)
			(layers "F.Cu" "F.Mask" "F.Paste")
			(net "MB_FRU_ADDR2")
		)
		(pad "2" smd circle
			(at 0.40005 0 180)
			(size 0 0)
			(layers "F.Cu" "F.Mask" "F.Paste")
			(net "GND")
		)
	)
	(footprint ""
		(layer "F.Cu")
		(at 285.689548 -413.23514 90)
		(property "Reference" "R4552"
			(at 0 0 90)
			(layer "F.SilkS")
			(hide yes)
			(effects
				(font
					(size 1.27 1.27)
				)
			)
		)
		(property "Value" ""
			(at 0 0 90)
			(layer "F.Fab")
			(effects
				(font
					(size 1.27 1.27)
				)
			)
		)
		(duplicate_pad_numbers_are_jumpers no)
		(fp_line
			(start 0.7874 -0.4064)
			(end 0.7874 0.4064)
			(stroke
				(width 0.1524)
				(type default)
			)
			(layer "F.SilkS")
		)
		(fp_line
			(start -0.7874 -0.4064)
			(end 0.7874 -0.4064)
			(stroke
				(width 0.1524)
				(type default)
			)
			(layer "F.SilkS")
		)
		(fp_line
			(start 0.7874 0.4064)
			(end -0.7874 0.4064)
			(stroke
				(width 0.1524)
				(type default)
			)
			(layer "F.SilkS")
		)
		(fp_line
			(start -0.7874 0.4064)
			(end -0.7874 -0.4064)
			(stroke
				(width 0.1524)
				(type default)
			)
			(layer "F.SilkS")
		)
		(fp_line
			(start -0.12065 -0.305054)
			(end -0.12065 -0.2794)
			(stroke
				(width 0.1)
				(type default)
			)
			(layer "F.Fab")
		)
		(fp_line
			(start -0.67945 -0.305054)
			(end -0.12065 -0.305054)
			(stroke
				(width 0.1)
				(type default)
			)
			(layer "F.Fab")
		)
		(fp_line
			(start 0.67945 -0.3048)
			(end 0.67945 0.3048)
			(stroke
				(width 0.1)
				(type default)
			)
			(layer "F.Fab")
		)
		(fp_line
			(start 0.12065 -0.3048)
			(end 0.67945 -0.3048)
			(stroke
				(width 0.1)
				(type default)
			)
			(layer "F.Fab")
		)
		(fp_line
			(start 0.12065 -0.2794)
			(end 0.12065 -0.3048)
			(stroke
				(width 0.1)
				(type default)
			)
			(layer "F.Fab")
		)
		(fp_line
			(start -0.12065 -0.2794)
			(end 0.12065 -0.2794)
			(stroke
				(width 0.1)
				(type default)
			)
			(layer "F.Fab")
		)
		(fp_line
			(start 0.120396 0.2794)
			(end -0.12065 0.2794)
			(stroke
				(width 0.1)
				(type default)
			)
			(layer "F.Fab")
		)
		(fp_line
			(start -0.12065 0.2794)
			(end -0.12065 0.3048)
			(stroke
				(width 0.1)
				(type default)
			)
			(layer "F.Fab")
		)
		(fp_line
			(start 0.67945 0.3048)
			(end 0.120396 0.3048)
			(stroke
				(width 0.1)
				(type default)
			)
			(layer "F.Fab")
		)
		(fp_line
			(start 0.120396 0.3048)
			(end 0.120396 0.2794)
			(stroke
				(width 0.1)
				(type default)
			)
			(layer "F.Fab")
		)
		(fp_line
			(start -0.12065 0.3048)
			(end -0.67945 0.3048)
			(stroke
				(width 0.1)
				(type default)
			)
			(layer "F.Fab")
		)
		(fp_line
			(start -0.67945 0.3048)
			(end -0.67945 -0.305054)
			(stroke
				(width 0.1)
				(type default)
			)
			(layer "F.Fab")
		)
		(pad "1" smd circle
			(at -0.40005 0 90)
			(size 0 0)
			(layers "F.Cu" "F.Mask" "F.Paste")
			(net "HPDB_HSC_PWRGD")
		)
		(pad "2" smd circle
			(at 0.40005 0 90)
			(size 0 0)
			(layers "F.Cu" "F.Mask" "F.Paste")
			(net "GND")
		)
	)
)
